(kicad_pcb
	(version 20260206)
	(generator "pcbnew")
	(generator_version "10.0")
	(general
		(thickness 1.6)
		(legacy_teardrops no)
	)
	(paper "A4")
	(title_block
		(title "pdpb — Lightning_PDPB_BRD.brd")
		(comment 1 "Lightning (Wiwynn / Facebook NVMe JBOF) / footprints 1075-1080 of 1140")
	)
	(layers
		(0 "F.Cu" signal "TOP")
		(4 "In1.Cu" signal "L2GND")
		(6 "In2.Cu" signal "L3")
		(8 "In3.Cu" signal "L4VCC")
		(10 "In4.Cu" signal "L5VCC")
		(12 "In5.Cu" signal "L6")
		(14 "In6.Cu" signal "L7GND")
		(2 "B.Cu" signal "BOTTOM")
		(9 "F.Adhes" user "F.Adhesive")
		(11 "B.Adhes" user "B.Adhesive")
		(13 "F.Paste" user "Package Geometry/Pastemask Top")
		(15 "B.Paste" user "Package Geometry/Pastemask Bottom")
		(5 "F.SilkS" user "Ref Des/Silkscreen Top")
		(7 "B.SilkS" user "Ref Des/Silkscreen Bottom")
		(1 "F.Mask" user "Board Geometry/Soldermask Top")
		(3 "B.Mask" user "Board Geometry/Soldermask Bottom")
		(17 "Dwgs.User" user "User.Drawings")
		(19 "Cmts.User" user "User.Comments")
		(21 "Eco1.User" user "User.Eco1")
		(23 "Eco2.User" user "User.Eco2")
		(25 "Edge.Cuts" user "Board Geometry/Outline")
		(27 "Margin" user)
		(31 "F.CrtYd" user "Package Geometry/Place Bound Top")
		(29 "B.CrtYd" user "Package Geometry/Place Bound Bottom")
		(35 "F.Fab" user "Ref Des/Assembly Top")
		(33 "B.Fab" user "Ref Des/Assembly Bottom")
	)
	(footprint ""
		(layer "F.Cu")
		(at 200.873106 -492.634778 -90)
		(property "Reference" "R137"
			(at 0 0 270)
			(layer "F.SilkS")
			(hide yes)
			(effects
				(font
					(size 1.27 1.27)
				)
			)
		)
		(property "Value" "4K7R2J-2-GP"
			(at 0.064008 -3.993896 270)
			(unlocked yes)
			(layer "F.Fab")
			(hide yes)
			(effects
				(font
					(size 1.016 1.016)
					(thickness 0.1524)
				)
			)
		)
		(property "Device Type" "R402H16"
			(at 0.064008 -5.517896 270)
			(unlocked yes)
			(layer "F.Fab")
			(hide yes)
			(effects
				(font
					(size 1.016 1.016)
					(thickness 0.1524)
				)
			)
		)
		(duplicate_pad_numbers_are_jumpers no)
		(fp_line
			(start -0.508 -0.9398)
			(end -0.508 0.9398)
			(stroke
				(width 0.1524)
				(type default)
			)
			(layer "F.SilkS")
		)
		(fp_line
			(start 0.508 -0.9398)
			(end -0.508 -0.9398)
			(stroke
				(width 0.1524)
				(type default)
			)
			(layer "F.SilkS")
		)
		(fp_poly
			(pts
				(xy -0.508 0.9398) (xy 0.508 0.9398) (xy 0.508 -0.9398) (xy -0.508 -0.9398)
			)
			(stroke
				(width 0)
				(type default)
			)
			(fill no)
			(layer "F.CrtYd")
		)
		(fp_rect
			(start -0.508 0.9398)
			(end 0.508 -0.9398)
			(stroke
				(width 0)
				(type default)
			)
			(fill no)
			(layer "F.Fab")
		)
		(pad "1" smd custom
			(at 0 -0.4445 270)
			(size 0.1397 0.1397)
			(layers "F.Cu" "F.Mask" "F.Paste")
			(net "P12V")
			(options
				(clearance outline)
				(anchor circle)
			)
			(primitives
				(gr_poly
					(pts
						(arc
							(start -0.1778 -0.2794)
							(mid -0.249642 -0.249642)
							(end -0.2794 -0.1778)
						)
						(arc
							(start -0.2794 0.1778)
							(mid -0.249642 0.249642)
							(end -0.1778 0.2794)
						)
						(arc
							(start 0.1778 0.2794)
							(mid 0.249642 0.249642)
							(end 0.2794 0.1778)
						)
						(arc
							(start 0.2794 -0.1778)
							(mid 0.249642 -0.249642)
							(end 0.1778 -0.2794)
						)
					)
					(width 0)
					(fill yes)
				)
			)
		)
		(pad "2" smd custom
			(at 0 0.4445 270)
			(size 0.1397 0.1397)
			(layers "F.Cu" "F.Mask" "F.Paste")
			(net "SW_SSD0_R")
			(options
				(clearance outline)
				(anchor circle)
			)
			(primitives
				(gr_poly
					(pts
						(arc
							(start -0.1778 -0.2794)
							(mid -0.249642 -0.249642)
							(end -0.2794 -0.1778)
						)
						(arc
							(start -0.2794 0.1778)
							(mid -0.249642 0.249642)
							(end -0.1778 0.2794)
						)
						(arc
							(start 0.1778 0.2794)
							(mid 0.249642 0.249642)
							(end 0.2794 0.1778)
						)
						(arc
							(start 0.2794 -0.1778)
							(mid 0.249642 -0.249642)
							(end 0.1778 -0.2794)
						)
					)
					(width 0)
					(fill yes)
				)
			)
		)
	)
	(footprint ""
		(layer "F.Cu")
		(at 18.5674 -473.3036)
		(property "Reference" "Q79"
			(at 0 0 0)
			(layer "F.SilkS")
			(hide yes)
			(effects
				(font
					(size 1.27 1.27)
				)
			)
		)
		(property "Value" "2N7002A-7-GP"
			(at 0.127 -8.9662 0)
			(unlocked yes)
			(layer "F.Fab")
			(hide yes)
			(effects
				(font
					(size 1.016 1.016)
					(thickness 0.1524)
				)
			)
		)
		(property "Device Type" "SOT23DGS2D4H48"
			(at 0.127 -10.4902 0)
			(unlocked yes)
			(layer "F.Fab")
			(hide yes)
			(effects
				(font
					(size 1.016 1.016)
					(thickness 0.1524)
				)
			)
		)
		(duplicate_pad_numbers_are_jumpers no)
		(fp_line
			(start -1.651 -1.778)
			(end -1.651 1.778)
			(stroke
				(width 0.1524)
				(type default)
			)
			(layer "F.SilkS")
		)
		(fp_line
			(start -1.651 1.778)
			(end 1.651 1.778)
			(stroke
				(width 0.1524)
				(type default)
			)
			(layer "F.SilkS")
		)
		(fp_line
			(start 1.651 -1.778)
			(end -1.651 -1.778)
			(stroke
				(width 0.1524)
				(type default)
			)
			(layer "F.SilkS")
		)
		(fp_line
			(start 1.651 1.778)
			(end 1.651 -1.778)
			(stroke
				(width 0.1524)
				(type default)
			)
			(layer "F.SilkS")
		)
		(fp_poly
			(pts
				(xy -1.778 1.8796) (xy -1.778 -1.8796) (xy 1.778 -1.8796) (xy 1.778 1.8796)
			)
			(stroke
				(width 0)
				(type default)
			)
			(fill no)
			(layer "F.CrtYd")
		)
		(fp_poly
			(pts
				(xy -1.778 1.8796) (xy -1.778 -1.8796) (xy 1.778 -1.8796) (xy 1.778 1.8796)
			)
			(stroke
				(width 0)
				(type default)
			)
			(fill no)
			(layer "F.Fab")
		)
		(pad "D" smd custom
			(at 0 -0.9525)
			(size 0.1905 0.1905)
			(layers "F.Cu" "F.Mask" "F.Paste")
			(net "SSD10_CLK0_OE_MOS_N")
			(options
				(clearance outline)
				(anchor circle)
			)
			(primitives
				(gr_poly
					(pts
						(arc
							(start -0.1778 0.5715)
							(mid -0.321484 0.511984)
							(end -0.381 0.3683)
						)
						(arc
							(start -0.381 -0.3683)
							(mid -0.321484 -0.511984)
							(end -0.1778 -0.5715)
						)
						(arc
							(start 0.1778 -0.5715)
							(mid 0.321484 -0.511984)
							(end 0.381 -0.3683)
						)
						(arc
							(start 0.381 0.3683)
							(mid 0.321484 0.511984)
							(end 0.1778 0.5715)
						)
					)
					(width 0)
					(fill yes)
				)
			)
		)
		(pad "G" smd custom
			(at -0.98425 0.9525)
			(size 0.1905 0.1905)
			(layers "F.Cu" "F.Mask" "F.Paste")
			(net "SSD10_CLK0_OE_R_N")
			(options
				(clearance outline)
				(anchor circle)
			)
			(primitives
				(gr_poly
					(pts
						(arc
							(start -0.1778 0.5715)
							(mid -0.321484 0.511984)
							(end -0.381 0.3683)
						)
						(arc
							(start -0.381 -0.3683)
							(mid -0.321484 -0.511984)
							(end -0.1778 -0.5715)
						)
						(arc
							(start 0.1778 -0.5715)
							(mid 0.321484 -0.511984)
							(end 0.381 -0.3683)
						)
						(arc
							(start 0.381 0.3683)
							(mid 0.321484 0.511984)
							(end 0.1778 0.5715)
						)
					)
					(width 0)
					(fill yes)
				)
			)
		)
		(pad "S" smd custom
			(at 0.98425 0.9525)
			(size 0.1905 0.1905)
			(layers "F.Cu" "F.Mask" "F.Paste")
			(net "GND")
			(options
				(clearance outline)
				(anchor circle)
			)
			(primitives
				(gr_poly
					(pts
						(arc
							(start -0.1778 0.5715)
							(mid -0.321484 0.511984)
							(end -0.381 0.3683)
						)
						(arc
							(start -0.381 -0.3683)
							(mid -0.321484 -0.511984)
							(end -0.1778 -0.5715)
						)
						(arc
							(start 0.1778 -0.5715)
							(mid 0.321484 -0.511984)
							(end 0.381 -0.3683)
						)
						(arc
							(start 0.381 0.3683)
							(mid 0.321484 0.511984)
							(end 0.1778 0.5715)
						)
					)
					(width 0)
					(fill yes)
				)
			)
		)
	)
	(footprint ""
		(layer "F.Cu")
		(at 31.369 -94.9706 -90)
		(property "Reference" "Q72"
			(at 0 0 270)
			(layer "F.SilkS")
			(hide yes)
			(effects
				(font
					(size 1.27 1.27)
				)
			)
		)
		(property "Value" "2N7002A-7-GP"
			(at 0.127 -8.9662 270)
			(unlocked yes)
			(layer "F.Fab")
			(hide yes)
			(effects
				(font
					(size 1.016 1.016)
					(thickness 0.1524)
				)
			)
		)
		(property "Device Type" "SOT23DGS2D4H48"
			(at 0.127 -10.4902 270)
			(unlocked yes)
			(layer "F.Fab")
			(hide yes)
			(effects
				(font
					(size 1.016 1.016)
					(thickness 0.1524)
				)
			)
		)
		(duplicate_pad_numbers_are_jumpers no)
		(fp_line
			(start -1.651 1.778)
			(end 1.651 1.778)
			(stroke
				(width 0.1524)
				(type default)
			)
			(layer "F.SilkS")
		)
		(fp_line
			(start 1.651 1.778)
			(end 1.651 -1.778)
			(stroke
				(width 0.1524)
				(type default)
			)
			(layer "F.SilkS")
		)
		(fp_line
			(start -1.651 -1.778)
			(end -1.651 1.778)
			(stroke
				(width 0.1524)
				(type default)
			)
			(layer "F.SilkS")
		)
		(fp_line
			(start 1.651 -1.778)
			(end -1.651 -1.778)
			(stroke
				(width 0.1524)
				(type default)
			)
			(layer "F.SilkS")
		)
		(fp_poly
			(pts
				(xy -1.778 1.8796) (xy -1.778 -1.8796) (xy 1.778 -1.8796) (xy 1.778 1.8796)
			)
			(stroke
				(width 0)
				(type default)
			)
			(fill no)
			(layer "F.CrtYd")
		)
		(fp_poly
			(pts
				(xy -1.778 1.8796) (xy -1.778 -1.8796) (xy 1.778 -1.8796) (xy 1.778 1.8796)
			)
			(stroke
				(width 0)
				(type default)
			)
			(fill no)
			(layer "F.Fab")
		)
		(pad "D" smd custom
			(at 0 -0.9525 270)
			(size 0.1905 0.1905)
			(layers "F.Cu" "F.Mask" "F.Paste")
			(net "P12V_MOST9_GATE_D")
			(options
				(clearance outline)
				(anchor circle)
			)
			(primitives
				(gr_poly
					(pts
						(arc
							(start -0.1778 0.5715)
							(mid -0.321484 0.511984)
							(end -0.381 0.3683)
						)
						(arc
							(start -0.381 -0.3683)
							(mid -0.321484 -0.511984)
							(end -0.1778 -0.5715)
						)
						(arc
							(start 0.1778 -0.5715)
							(mid 0.321484 -0.511984)
							(end 0.381 -0.3683)
						)
						(arc
							(start 0.381 0.3683)
							(mid 0.321484 0.511984)
							(end 0.1778 0.5715)
						)
					)
					(width 0)
					(fill yes)
				)
			)
		)
		(pad "G" smd custom
			(at -0.98425 0.9525 270)
			(size 0.1905 0.1905)
			(layers "F.Cu" "F.Mask" "F.Paste")
			(net "P12V_MOST9_GATE")
			(options
				(clearance outline)
				(anchor circle)
			)
			(primitives
				(gr_poly
					(pts
						(arc
							(start -0.1778 0.5715)
							(mid -0.321484 0.511984)
							(end -0.381 0.3683)
						)
						(arc
							(start -0.381 -0.3683)
							(mid -0.321484 -0.511984)
							(end -0.1778 -0.5715)
						)
						(arc
							(start 0.1778 -0.5715)
							(mid 0.321484 -0.511984)
							(end 0.381 -0.3683)
						)
						(arc
							(start 0.381 0.3683)
							(mid 0.321484 0.511984)
							(end 0.1778 0.5715)
						)
					)
					(width 0)
					(fill yes)
				)
			)
		)
		(pad "S" smd custom
			(at 0.98425 0.9525 270)
			(size 0.1905 0.1905)
			(layers "F.Cu" "F.Mask" "F.Paste")
			(net "GND")
			(options
				(clearance outline)
				(anchor circle)
			)
			(primitives
				(gr_poly
					(pts
						(arc
							(start -0.1778 0.5715)
							(mid -0.321484 0.511984)
							(end -0.381 0.3683)
						)
						(arc
							(start -0.381 -0.3683)
							(mid -0.321484 -0.511984)
							(end -0.1778 -0.5715)
						)
						(arc
							(start 0.1778 -0.5715)
							(mid 0.321484 -0.511984)
							(end 0.381 -0.3683)
						)
						(arc
							(start 0.381 0.3683)
							(mid 0.321484 0.511984)
							(end 0.1778 0.5715)
						)
					)
					(width 0)
					(fill yes)
				)
			)
		)
	)
	(footprint ""
		(layer "F.Cu")
		(at 29.718 -421.513)
		(property "Reference" "SR1112"
			(at 0 0 0)
			(layer "F.SilkS")
			(hide yes)
			(effects
				(font
					(size 1.27 1.27)
				)
			)
		)
		(property "Value" "4K7R2F-GP"
			(at 0.064008 -3.993896 0)
			(unlocked yes)
			(layer "F.Fab")
			(hide yes)
			(effects
				(font
					(size 1.016 1.016)
					(thickness 0.1524)
				)
			)
		)
		(property "Device Type" "R402H16"
			(at 0.064008 -5.517896 0)
			(unlocked yes)
			(layer "F.Fab")
			(hide yes)
			(effects
				(font
					(size 1.016 1.016)
					(thickness 0.1524)
				)
			)
		)
		(duplicate_pad_numbers_are_jumpers no)
		(fp_line
			(start -0.508 -0.9398)
			(end -0.508 0.9398)
			(stroke
				(width 0.1524)
				(type default)
			)
			(layer "F.SilkS")
		)
		(fp_line
			(start 0.508 -0.9398)
			(end -0.508 -0.9398)
			(stroke
				(width 0.1524)
				(type default)
			)
			(layer "F.SilkS")
		)
		(fp_rect
			(start -0.508 0.9398)
			(end 0.508 -0.9398)
			(stroke
				(width 0)
				(type default)
			)
			(fill no)
			(layer "F.CrtYd")
		)
		(fp_rect
			(start -0.508 0.9398)
			(end 0.508 -0.9398)
			(stroke
				(width 0)
				(type default)
			)
			(fill no)
			(layer "F.Fab")
		)
		(pad "1" smd custom
			(at 0 -0.4445)
			(size 0.1397 0.1397)
			(layers "F.Cu" "F.Mask" "F.Paste")
			(net "DUALPORTEN#10")
			(options
				(clearance outline)
				(anchor circle)
			)
			(primitives
				(gr_poly
					(pts
						(arc
							(start -0.1778 -0.2794)
							(mid -0.249642 -0.249642)
							(end -0.2794 -0.1778)
						)
						(arc
							(start -0.2794 0.1778)
							(mid -0.249642 0.249642)
							(end -0.1778 0.2794)
						)
						(arc
							(start 0.1778 0.2794)
							(mid 0.249642 0.249642)
							(end 0.2794 0.1778)
						)
						(arc
							(start 0.2794 -0.1778)
							(mid 0.249642 -0.249642)
							(end 0.1778 -0.2794)
						)
					)
					(width 0)
					(fill yes)
				)
			)
		)
		(pad "2" smd custom
			(at 0 0.4445)
			(size 0.1397 0.1397)
			(layers "F.Cu" "F.Mask" "F.Paste")
			(net "GND")
			(options
				(clearance outline)
				(anchor circle)
			)
			(primitives
				(gr_poly
					(pts
						(arc
							(start -0.1778 -0.2794)
							(mid -0.249642 -0.249642)
							(end -0.2794 -0.1778)
						)
						(arc
							(start -0.2794 0.1778)
							(mid -0.249642 0.249642)
							(end -0.1778 0.2794)
						)
						(arc
							(start 0.1778 0.2794)
							(mid 0.249642 0.249642)
							(end 0.2794 0.1778)
						)
						(arc
							(start 0.2794 -0.1778)
							(mid 0.249642 -0.249642)
							(end 0.1778 -0.2794)
						)
					)
					(width 0)
					(fill yes)
				)
			)
		)
	)
	(footprint ""
		(layer "F.Cu")
		(at 35.687 -347.48089)
		(property "Reference" "Q60"
			(at 0 0 0)
			(layer "F.SilkS")
			(hide yes)
			(effects
				(font
					(size 1.27 1.27)
				)
			)
		)
		(property "Value" "2N7002A-7-GP"
			(at 0.127 -8.9662 0)
			(unlocked yes)
			(layer "F.Fab")
			(hide yes)
			(effects
				(font
					(size 1.016 1.016)
					(thickness 0.1524)
				)
			)
		)
		(property "Device Type" "SOT23DGS2D4H48"
			(at 0.127 -10.4902 0)
			(unlocked yes)
			(layer "F.Fab")
			(hide yes)
			(effects
				(font
					(size 1.016 1.016)
					(thickness 0.1524)
				)
			)
		)
		(duplicate_pad_numbers_are_jumpers no)
		(fp_line
			(start -1.651 -1.778)
			(end -1.651 1.778)
			(stroke
				(width 0.1524)
				(type default)
			)
			(layer "F.SilkS")
		)
		(fp_line
			(start -1.651 1.778)
			(end 1.651 1.778)
			(stroke
				(width 0.1524)
				(type default)
			)
			(layer "F.SilkS")
		)
		(fp_line
			(start 1.651 -1.778)
			(end -1.651 -1.778)
			(stroke
				(width 0.1524)
				(type default)
			)
			(layer "F.SilkS")
		)
		(fp_line
			(start 1.651 1.778)
			(end 1.651 -1.778)
			(stroke
				(width 0.1524)
				(type default)
			)
			(layer "F.SilkS")
		)
		(fp_poly
			(pts
				(xy -1.778 1.8796) (xy -1.778 -1.8796) (xy 1.778 -1.8796) (xy 1.778 1.8796)
			)
			(stroke
				(width 0)
				(type default)
			)
			(fill no)
			(layer "F.CrtYd")
		)
		(fp_poly
			(pts
				(xy -1.778 1.8796) (xy -1.778 -1.8796) (xy 1.778 -1.8796) (xy 1.778 1.8796)
			)
			(stroke
				(width 0)
				(type default)
			)
			(fill no)
			(layer "F.Fab")
		)
		(pad "D" smd custom
			(at 0 -0.9525)
			(size 0.1905 0.1905)
			(layers "F.Cu" "F.Mask" "F.Paste")
			(net "ATTN_LED_DR6_MOS_N")
			(options
				(clearance outline)
				(anchor circle)
			)
			(primitives
				(gr_poly
					(pts
						(arc
							(start -0.1778 0.5715)
							(mid -0.321484 0.511984)
							(end -0.381 0.3683)
						)
						(arc
							(start -0.381 -0.3683)
							(mid -0.321484 -0.511984)
							(end -0.1778 -0.5715)
						)
						(arc
							(start 0.1778 -0.5715)
							(mid 0.321484 -0.511984)
							(end 0.381 -0.3683)
						)
						(arc
							(start 0.381 0.3683)
							(mid 0.321484 0.511984)
							(end 0.1778 0.5715)
						)
					)
					(width 0)
					(fill yes)
				)
			)
		)
		(pad "G" smd custom
			(at -0.98425 0.9525)
			(size 0.1905 0.1905)
			(layers "F.Cu" "F.Mask" "F.Paste")
			(net "SSD6_CLK0_OE_MOS_N")
			(options
				(clearance outline)
				(anchor circle)
			)
			(primitives
				(gr_poly
					(pts
						(arc
							(start -0.1778 0.5715)
							(mid -0.321484 0.511984)
							(end -0.381 0.3683)
						)
						(arc
							(start -0.381 -0.3683)
							(mid -0.321484 -0.511984)
							(end -0.1778 -0.5715)
						)
						(arc
							(start 0.1778 -0.5715)
							(mid 0.321484 -0.511984)
							(end 0.381 -0.3683)
						)
						(arc
							(start 0.381 0.3683)
							(mid 0.321484 0.511984)
							(end 0.1778 0.5715)
						)
					)
					(width 0)
					(fill yes)
				)
			)
		)
		(pad "S" smd custom
			(at 0.98425 0.9525)
			(size 0.1905 0.1905)
			(layers "F.Cu" "F.Mask" "F.Paste")
			(net "ATTN_LED_DR6_R")
			(options
				(clearance outline)
				(anchor circle)
			)
			(primitives
				(gr_poly
					(pts
						(arc
							(start -0.1778 0.5715)
							(mid -0.321484 0.511984)
							(end -0.381 0.3683)
						)
						(arc
							(start -0.381 -0.3683)
							(mid -0.321484 -0.511984)
							(end -0.1778 -0.5715)
						)
						(arc
							(start 0.1778 -0.5715)
							(mid 0.321484 -0.511984)
							(end 0.381 -0.3683)
						)
						(arc
							(start 0.381 0.3683)
							(mid 0.321484 0.511984)
							(end 0.1778 0.5715)
						)
					)
					(width 0)
					(fill yes)
				)
			)
		)
	)
	(footprint ""
		(layer "F.Cu")
		(at 25.4 -445.135 180)
		(property "Reference" "PC1184"
			(at 0 0 180)
			(layer "F.SilkS")
			(hide yes)
			(effects
				(font
					(size 1.27 1.27)
				)
			)
		)
		(property "Value" "SCD1U25V3KX-GP"
			(at 0 -2.8194 180)
			(unlocked yes)
			(layer "F.Fab")
			(hide yes)
			(effects
				(font
					(size 1.016 1.016)
					(thickness 0.1524)
				)
			)
		)
		(property "Device Type" "C603H36"
			(at 0 -4.3434 180)
			(unlocked yes)
			(layer "F.Fab")
			(hide yes)
			(effects
				(font
					(size 1.016 1.016)
					(thickness 0.1524)
				)
			)
		)
		(duplicate_pad_numbers_are_jumpers no)
		(fp_line
			(start 0.508 0)
			(end -0.508 0)
			(stroke
				(width 0.2032)
				(type default)
			)
			(layer "F.SilkS")
		)
		(fp_rect
			(start -0.5842 1.3335)
			(end 0.5842 -1.3335)
			(stroke
				(width 0)
				(type default)
			)
			(fill no)
			(layer "F.CrtYd")
		)
		(fp_rect
			(start -0.5842 1.3335)
			(end 0.5842 -1.3335)
			(stroke
				(width 0)
				(type default)
			)
			(fill no)
			(layer "F.Fab")
		)
		(pad "1" smd custom
			(at 0 -0.762 180)
			(size 0.2159 0.2159)
			(layers "F.Cu" "F.Mask" "F.Paste")
			(net "P3V3")
			(options
				(clearance outline)
				(anchor circle)
			)
			(primitives
				(gr_poly
					(pts
						(arc
							(start -0.3302 -0.4318)
							(mid -0.402042 -0.402042)
							(end -0.4318 -0.3302)
						)
						(arc
							(start -0.4318 0.3302)
							(mid -0.402042 0.402042)
							(end -0.3302 0.4318)
						)
						(arc
							(start 0.3302 0.4318)
							(mid 0.402042 0.402042)
							(end 0.4318 0.3302)
						)
						(arc
							(start 0.4318 -0.3302)
							(mid 0.402042 -0.402042)
							(end 0.3302 -0.4318)
						)
					)
					(width 0)
					(fill yes)
				)
			)
		)
		(pad "2" smd custom
			(at 0 0.762 180)
			(size 0.2159 0.2159)
			(layers "F.Cu" "F.Mask" "F.Paste")
			(net "GND")
			(options
				(clearance outline)
				(anchor circle)
			)
			(primitives
				(gr_poly
					(pts
						(arc
							(start -0.3302 -0.4318)
							(mid -0.402042 -0.402042)
							(end -0.4318 -0.3302)
						)
						(arc
							(start -0.4318 0.3302)
							(mid -0.402042 0.402042)
							(end -0.3302 0.4318)
						)
						(arc
							(start 0.3302 0.4318)
							(mid 0.402042 0.402042)
							(end 0.4318 0.3302)
						)
						(arc
							(start 0.4318 -0.3302)
							(mid 0.402042 -0.402042)
							(end 0.3302 -0.4318)
						)
					)
					(width 0)
					(fill yes)
				)
			)
		)
	)
)
